# T6G (Grand Teton) — schematic netlist excerpt (pin names and nets, part order shuffled) for the footprints in the layout excerpt that follows; sources: Cadence DE-HDL packaged netlist, KiCad conversion of 04192023_DAF0TMB3IC0_F0TG_MB_C_brd_V02_OCP.brd

R721  Q_RES  10K 1% CHIP  pkg 0402LF  page 238 : A = P3V3_AUX ; B = MB_FRU_ADDR0
R279  Q_RES  33 5% CHIP  pkg 0402LF  page 81 : A = PVDD11_S3_P1_EN ; B = FM_PVDD11_S3_P1_EN

(kicad_pcb
	(version 20260206)
	(generator "pcbnew")
	(generator_version "10.0")
	(general
		(thickness 1.6)
		(legacy_teardrops no)
	)
	(paper "A4")
	(title_block
		(title "04192023_DAF0TMB3IC0_F0TG_MB_C_brd_V02_OCP.brd")
		(comment 1 "Grand Teton / footprints 3786-3787 of 8354")
	)
	(layers
		(0 "F.Cu" signal "TOP")
		(4 "In1.Cu" signal "GND")
		(6 "In2.Cu" signal "IN1")
		(8 "In3.Cu" signal "GND1")
		(10 "In4.Cu" signal "IN2")
		(12 "In5.Cu" signal "GND2")
		(14 "In6.Cu" signal "IN3")
		(16 "In7.Cu" signal "GND3")
		(18 "In8.Cu" signal "VCC")
		(20 "In9.Cu" signal "VCC1")
		(22 "In10.Cu" signal "GND4")
		(24 "In11.Cu" signal "IN4")
		(26 "In12.Cu" signal "GND5")
		(28 "In13.Cu" signal "IN5")
		(30 "In14.Cu" signal "GND6")
		(32 "In15.Cu" signal "IN6")
		(34 "In16.Cu" signal "GND7")
		(2 "B.Cu" signal "BOTTOM")
		(9 "F.Adhes" user "F.Adhesive")
		(11 "B.Adhes" user "B.Adhesive")
		(13 "F.Paste" user "Package Geometry/Pastemask Top")
		(15 "B.Paste" user "Package Geometry/Pastemask Bottom")
		(5 "F.SilkS" user "Ref Des/Silkscreen Top")
		(7 "B.SilkS" user "Ref Des/Silkscreen Bottom")
		(1 "F.Mask" user "Board Geometry/Soldermask Top")
		(3 "B.Mask" user "Board Geometry/Soldermask Bottom")
		(17 "Dwgs.User" user "User.Drawings")
		(19 "Cmts.User" user "User.Comments")
		(21 "Eco1.User" user "User.Eco1")
		(23 "Eco2.User" user "User.Eco2")
		(25 "Edge.Cuts" user "Board Geometry/Outline")
		(27 "Margin" user)
		(31 "F.CrtYd" user "Package Geometry/Place Bound Top")
		(29 "B.CrtYd" user "Package Geometry/Place Bound Bottom")
		(35 "F.Fab" user "Ref Des/Assembly Top")
		(33 "B.Fab" user "Ref Des/Assembly Bottom")
	)
	(footprint ""
		(layer "F.Cu")
		(at 305.197002 -119.475504)
		(property "Reference" "R721"
			(at 0 0 0)
			(layer "F.SilkS")
			(hide yes)
			(effects
				(font
					(size 1.27 1.27)
				)
			)
		)
		(property "Value" ""
			(at 0 0 0)
			(layer "F.Fab")
			(effects
				(font
					(size 1.27 1.27)
				)
			)
		)
		(duplicate_pad_numbers_are_jumpers no)
		(fp_line
			(start -0.7874 -0.4064)
			(end 0.7874 -0.4064)
			(stroke
				(width 0.1524)
				(type default)
			)
			(layer "F.SilkS")
		)
		(fp_line
			(start -0.7874 0.4064)
			(end -0.7874 -0.4064)
			(stroke
				(width 0.1524)
				(type default)
			)
			(layer "F.SilkS")
		)
		(fp_line
			(start 0.7874 -0.4064)
			(end 0.7874 0.4064)
			(stroke
				(width 0.1524)
				(type default)
			)
			(layer "F.SilkS")
		)
		(fp_line
			(start 0.7874 0.4064)
			(end -0.7874 0.4064)
			(stroke
				(width 0.1524)
				(type default)
			)
			(layer "F.SilkS")
		)
		(fp_line
			(start -0.67945 -0.305054)
			(end -0.12065 -0.305054)
			(stroke
				(width 0.1)
				(type default)
			)
			(layer "F.Fab")
		)
		(fp_line
			(start -0.67945 0.3048)
			(end -0.67945 -0.305054)
			(stroke
				(width 0.1)
				(type default)
			)
			(layer "F.Fab")
		)
		(fp_line
			(start -0.12065 -0.305054)
			(end -0.12065 -0.2794)
			(stroke
				(width 0.1)
				(type default)
			)
			(layer "F.Fab")
		)
		(fp_line
			(start -0.12065 -0.2794)
			(end 0.12065 -0.2794)
			(stroke
				(width 0.1)
				(type default)
			)
			(layer "F.Fab")
		)
		(fp_line
			(start -0.12065 0.2794)
			(end -0.12065 0.3048)
			(stroke
				(width 0.1)
				(type default)
			)
			(layer "F.Fab")
		)
		(fp_line
			(start -0.12065 0.3048)
			(end -0.67945 0.3048)
			(stroke
				(width 0.1)
				(type default)
			)
			(layer "F.Fab")
		)
		(fp_line
			(start 0.120396 0.2794)
			(end -0.12065 0.2794)
			(stroke
				(width 0.1)
				(type default)
			)
			(layer "F.Fab")
		)
		(fp_line
			(start 0.120396 0.3048)
			(end 0.120396 0.2794)
			(stroke
				(width 0.1)
				(type default)
			)
			(layer "F.Fab")
		)
		(fp_line
			(start 0.12065 -0.3048)
			(end 0.67945 -0.3048)
			(stroke
				(width 0.1)
				(type default)
			)
			(layer "F.Fab")
		)
		(fp_line
			(start 0.12065 -0.2794)
			(end 0.12065 -0.3048)
			(stroke
				(width 0.1)
				(type default)
			)
			(layer "F.Fab")
		)
		(fp_line
			(start 0.67945 -0.3048)
			(end 0.67945 0.3048)
			(stroke
				(width 0.1)
				(type default)
			)
			(layer "F.Fab")
		)
		(fp_line
			(start 0.67945 0.3048)
			(end 0.120396 0.3048)
			(stroke
				(width 0.1)
				(type default)
			)
			(layer "F.Fab")
		)
		(pad "1" smd circle
			(at -0.40005 0)
			(size 0 0)
			(layers "F.Cu" "F.Mask" "F.Paste")
			(net "P3V3_AUX")
		)
		(pad "2" smd circle
			(at 0.40005 0)
			(size 0 0)
			(layers "F.Cu" "F.Mask" "F.Paste")
			(net "MB_FRU_ADDR0")
		)
	)
	(footprint ""
		(layer "F.Cu")
		(at 197.269608 -108.545376 180)
		(property "Reference" "R279"
			(at 0 0 180)
			(layer "F.SilkS")
			(hide yes)
			(effects
				(font
					(size 1.27 1.27)
				)
			)
		)
		(property "Value" ""
			(at 0 0 180)
			(layer "F.Fab")
			(effects
				(font
					(size 1.27 1.27)
				)
			)
		)
		(duplicate_pad_numbers_are_jumpers no)
		(fp_line
			(start 0.7874 0.4064)
			(end -0.7874 0.4064)
			(stroke
				(width 0.1524)
				(type default)
			)
			(layer "F.SilkS")
		)
		(fp_line
			(start 0.7874 -0.4064)
			(end 0.7874 0.4064)
			(stroke
				(width 0.1524)
				(type default)
			)
			(layer "F.SilkS")
		)
		(fp_line
			(start -0.7874 0.4064)
			(end -0.7874 -0.4064)
			(stroke
				(width 0.1524)
				(type default)
			)
			(layer "F.SilkS")
		)
		(fp_line
			(start -0.7874 -0.4064)
			(end 0.7874 -0.4064)
			(stroke
				(width 0.1524)
				(type default)
			)
			(layer "F.SilkS")
		)
		(fp_line
			(start 0.67945 0.3048)
			(end 0.120396 0.3048)
			(stroke
				(width 0.1)
				(type default)
			)
			(layer "F.Fab")
		)
		(fp_line
			(start 0.67945 -0.3048)
			(end 0.67945 0.3048)
			(stroke
				(width 0.1)
				(type default)
			)
			(layer "F.Fab")
		)
		(fp_line
			(start 0.12065 -0.2794)
			(end 0.12065 -0.3048)
			(stroke
				(width 0.1)
				(type default)
			)
			(layer "F.Fab")
		)
		(fp_line
			(start 0.12065 -0.3048)
			(end 0.67945 -0.3048)
			(stroke
				(width 0.1)
				(type default)
			)
			(layer "F.Fab")
		)
		(fp_line
			(start 0.120396 0.3048)
			(end 0.120396 0.2794)
			(stroke
				(width 0.1)
				(type default)
			)
			(layer "F.Fab")
		)
		(fp_line
			(start 0.120396 0.2794)
			(end -0.12065 0.2794)
			(stroke
				(width 0.1)
				(type default)
			)
			(layer "F.Fab")
		)
		(fp_line
			(start -0.12065 0.3048)
			(end -0.67945 0.3048)
			(stroke
				(width 0.1)
				(type default)
			)
			(layer "F.Fab")
		)
		(fp_line
			(start -0.12065 0.2794)
			(end -0.12065 0.3048)
			(stroke
				(width 0.1)
				(type default)
			)
			(layer "F.Fab")
		)
		(fp_line
			(start -0.12065 -0.2794)
			(end 0.12065 -0.2794)
			(stroke
				(width 0.1)
				(type default)
			)
			(layer "F.Fab")
		)
		(fp_line
			(start -0.12065 -0.305054)
			(end -0.12065 -0.2794)
			(stroke
				(width 0.1)
				(type default)
			)
			(layer "F.Fab")
		)
		(fp_line
			(start -0.67945 0.3048)
			(end -0.67945 -0.305054)
			(stroke
				(width 0.1)
				(type default)
			)
			(layer "F.Fab")
		)
		(fp_line
			(start -0.67945 -0.305054)
			(end -0.12065 -0.305054)
			(stroke
				(width 0.1)
				(type default)
			)
			(layer "F.Fab")
		)
		(pad "1" smd circle
			(at -0.40005 0 180)
			(size 0 0)
			(layers "F.Cu" "F.Mask" "F.Paste")
			(net "PVDD11_S3_P1_EN")
		)
		(pad "2" smd circle
			(at 0.40005 0 180)
			(size 0 0)
			(layers "F.Cu" "F.Mask" "F.Paste")
			(net "FM_PVDD11_S3_P1_EN")
		)
	)
)
